# scalenode-cm4-baseboard — symbol library table
(sym_lib_table
  (lib (name "scalenode-cm4-baseboard")(type "KiCad")(uri "${KIPRJMOD}/lib/scalenode-cm4-baseboard.kicad_sym")(options "")(descr ""))
)
